(kicad_pcb
	(version 20211014)
	(generator pcbnew)
	(general
    (thickness 1.6)
  )
	(paper "A4")
	(title_block
    (title "SA800U (Snapdragon 845) Baseboard")
    (date "2023-10-19")
    (rev "1.0.3")
    (company "Antmicro Ltd.")
    (comment 1 "www.antmicro.com")
		(comment 9 "footprints 214-215 of 589")
	)
	(layers
    (0 "F.Cu" signal)
    (1 "In1.Cu" power)
    (2 "In2.Cu" signal)
    (3 "In3.Cu" signal)
    (4 "In4.Cu" power)
    (31 "B.Cu" signal)
    (32 "B.Adhes" user "B.Adhesive")
    (33 "F.Adhes" user "F.Adhesive")
    (34 "B.Paste" user)
    (35 "F.Paste" user)
    (36 "B.SilkS" user "B.Silkscreen")
    (37 "F.SilkS" user "F.Silkscreen")
    (38 "B.Mask" user)
    (39 "F.Mask" user)
    (40 "Dwgs.User" user "User.Drawings")
    (41 "Cmts.User" user "User.Comments")
    (42 "Eco1.User" user "User.Eco1")
    (43 "Eco2.User" user "User.Eco2")
    (44 "Edge.Cuts" user)
    (45 "Margin" user)
    (46 "B.CrtYd" user "B.Courtyard")
    (47 "F.CrtYd" user "F.Courtyard")
    (48 "B.Fab" user)
    (49 "F.Fab" user)
  )
	(footprint "sa800u-baseboard-hw-footprints:QFN-64-1EP_7.5x7.5mm_P0.4mm" (layer "F.Cu")
    (tedit 6215E41B)
    (at 140.97322 125 -90)
    (property "Author" "Antmicro")
    (property "License" "Apache-2.0")
    (property "MPN" "LT9611")
    (property "Manufacturer" "Lontium")
    (property "Sheetfile" "hdmi-converter.kicad_sch")
    (property "Sheetname" "HDMI converter")
    (attr smd)
    (fp_text reference "U3" (at -4.53 -2.42678) (layer "F.SilkS")
      (effects (font (size 0.7 0.7) (thickness 0.15)) (justify left bottom))
    )
    (fp_text value "LT9611" (at 0 5.4 -90) (layer "F.Fab")
      (effects (font (size 0.7 0.7) (thickness 0.15)) (justify left bottom))
    )
    (fp_text user "License: Apache-2.0" (at -4.5 6.498 -90) (layer "F.Fab") hide
      (effects (font (size 0.7 0.7) (thickness 0.15)) (justify left bottom))
    )
    (fp_text user "Author: Antmicro" (at -4.5 8.897 -90) (layer "F.Fab") hide
      (effects (font (size 0.7 0.7) (thickness 0.15)) (justify left bottom))
    )
    (fp_text user "${REFERENCE}" (at -4.5 7.698 -90) (layer "F.Fab") hide
      (effects (font (size 0.7 0.7) (thickness 0.15)) (justify left bottom))
    )
    (fp_poly (pts
        (xy 0.726 0.77)
        (xy -0.774 0.77)
        (xy -0.774 -0.784)
        (xy 0.726 -0.784)
      ) (layer "F.Paste") (width 0.01) (fill solid))
    (fp_poly (pts
        (xy 0.726 -1.131)
        (xy -0.774 -1.131)
        (xy -0.774 -2.681)
        (xy 0.726 -2.681)
      ) (layer "F.Paste") (width 0.01) (fill solid))
    (fp_poly (pts
        (xy -2.681 1.126)
        (xy -1.18 1.126)
        (xy -1.18 2.68)
        (xy -2.681 2.68)
      ) (layer "F.Paste") (width 0.01) (fill solid))
    (fp_poly (pts
        (xy -1.17 0.77)
        (xy -2.67 0.77)
        (xy -2.67 -0.784)
        (xy -1.17 -0.784)
      ) (layer "F.Paste") (width 0.01) (fill solid))
    (fp_poly (pts
        (xy 1.169 1.126)
        (xy 2.668 1.126)
        (xy 2.668 2.68)
        (xy 1.169 2.68)
      ) (layer "F.Paste") (width 0.01) (fill solid))
    (fp_poly (pts
        (xy 2.68 0.77)
        (xy 1.179 0.77)
        (xy 1.179 -0.784)
        (xy 2.68 -0.784)
      ) (layer "F.Paste") (width 0.01) (fill solid))
    (fp_poly (pts
        (xy -0.73 1.126)
        (xy 0.77 1.126)
        (xy 0.77 2.68)
        (xy -0.73 2.68)
      ) (layer "F.Paste") (width 0.01) (fill solid))
    (fp_poly (pts
        (xy -1.17 -1.131)
        (xy -2.67 -1.131)
        (xy -2.67 -2.681)
        (xy -1.17 -2.681)
      ) (layer "F.Paste") (width 0.01) (fill solid))
    (fp_poly (pts
        (xy 2.68 -1.131)
        (xy 1.179 -1.131)
        (xy 1.179 -2.681)
        (xy 2.68 -2.681)
      ) (layer "F.Paste") (width 0.01) (fill solid))
    (fp_line (start 3.898 3.898) (end 3.898 3.398) (layer "F.SilkS") (width 0.15))
    (fp_line (start 3.398 -3.9) (end 3.898 -3.9) (layer "F.SilkS") (width 0.15))
    (fp_line (start 3.898 -3.9) (end 3.898 -3.4) (layer "F.SilkS") (width 0.15))
    (fp_line (start -3.9 -3.9) (end -3.4 -3.9) (layer "F.SilkS") (width 0.15))
    (fp_line (start -3.9 3.898) (end -3.9 3.398) (layer "F.SilkS") (width 0.15))
    (fp_line (start 3.398 3.898) (end 3.898 3.898) (layer "F.SilkS") (width 0.15))
    (fp_line (start -3.9 -3.4) (end -3.9 -3.9) (layer "F.SilkS") (width 0.15))
    (fp_line (start -3.4 3.898) (end -3.9 3.898) (layer "F.SilkS") (width 0.15))
    (fp_circle (center -4.202 -3.301) (end -4.151 -3.301) (layer "F.SilkS") (width 0.15) (fill solid))
    (fp_rect (start -4.4 -4.4) (end 4.4 4.4) (layer "F.CrtYd") (width 0.05) (fill none))
    (fp_line (start 3.749 -3.75) (end -2.75 -3.75) (layer "F.Fab") (width 0.15))
    (fp_line (start 3.749 3.749) (end 3.749 -3.75) (layer "F.Fab") (width 0.15))
    (fp_line (start -3.75 -2.75) (end -3.75 3.749) (layer "F.Fab") (width 0.15))
    (fp_line (start -2.75 -3.75) (end -3.75 -2.75) (layer "F.Fab") (width 0.15))
    (fp_line (start -3.75 3.749) (end 3.749 3.749) (layer "F.Fab") (width 0.15))
    (pad "1" smd rect (at -3.801 -3) (size 0.2 1) (layers "F.Cu" "F.Paste" "F.Mask")
      (net 484 "unconnected-(U3-Pad1)") (pinfunction "M0_N2") (pintype "unspecified+no_connect"))
    (pad "2" smd rect (at -3.801 -2.601) (size 0.2 1) (layers "F.Cu" "F.Paste" "F.Mask")
      (net 483 "unconnected-(U3-Pad2)") (pinfunction "M0_P2") (pintype "unspecified+no_connect"))
    (pad "3" smd rect (at -3.801 -2.202) (size 0.2 1) (layers "F.Cu" "F.Paste" "F.Mask")
      (net 185 "/HDMI converter/LT9611_VCC33_RX") (pinfunction "VCC33_MRX01") (pintype "power_in"))
    (pad "4" smd rect (at -3.801 -1.801) (size 0.2 1) (layers "F.Cu" "F.Paste" "F.Mask")
      (net 189 "/HDMI converter/LT9611_VCC12_RX") (pinfunction "VCC12_MRX01") (pintype "power_in"))
    (pad "5" smd rect (at -3.801 -1.401) (size 0.2 1) (layers "F.Cu" "F.Paste" "F.Mask")
      (net 54 "DSI1_LN3_N") (pinfunction "M3_N0") (pintype "input"))
    (pad "6" smd rect (at -3.801 -1) (size 0.2 1) (layers "F.Cu" "F.Paste" "F.Mask")
      (net 58 "DSI1_LN3_P") (pinfunction "M3_P0") (pintype "input"))
    (pad "7" smd rect (at -3.801 -0.6) (size 0.2 1) (layers "F.Cu" "F.Paste" "F.Mask")
      (net 53 "DSI1_LN2_N") (pinfunction "M2_N0") (pintype "input"))
    (pad "8" smd rect (at -3.801 -0.204) (size 0.2 1) (layers "F.Cu" "F.Paste" "F.Mask")
      (net 57 "DSI1_LN2_P") (pinfunction "M2_P0") (pintype "input"))
    (pad "9" smd rect (at -3.801 0.2) (size 0.2 1) (layers "F.Cu" "F.Paste" "F.Mask")
      (net 55 "DSI1_CLK_N") (pinfunction "MC_N0") (pintype "input"))
    (pad "10" smd rect (at -3.801 0.596) (size 0.2 1) (layers "F.Cu" "F.Paste" "F.Mask")
      (net 56 "DSI1_CLK_P") (pinfunction "MC_P0") (pintype "input"))
    (pad "11" smd rect (at -3.801 0.996) (size 0.2 1) (layers "F.Cu" "F.Paste" "F.Mask")
      (net 52 "DSI1_LN1_N") (pinfunction "M1_N0") (pintype "input"))
    (pad "12" smd rect (at -3.801 1.396) (size 0.2 1) (layers "F.Cu" "F.Paste" "F.Mask")
      (net 50 "DSI1_LN1_P") (pinfunction "M1_P0") (pintype "input"))
    (pad "13" smd rect (at -3.801 1.8) (size 0.2 1) (layers "F.Cu" "F.Paste" "F.Mask")
      (net 51 "DSI1_LN0_N") (pinfunction "M0_N0") (pintype "input"))
    (pad "14" smd rect (at -3.801 2.2) (size 0.2 1) (layers "F.Cu" "F.Paste" "F.Mask")
      (net 176 "DSI1_LN0_P") (pinfunction "M0_P0") (pintype "input"))
    (pad "15" smd rect (at -3.801 2.6) (size 0.2 1) (layers "F.Cu" "F.Paste" "F.Mask")
      (net 188 "/HDMI converter/LT9611_VDD12") (pinfunction "VDD1") (pintype "power_in"))
    (pad "16" smd rect (at -3.801 2.999) (size 0.2 1) (layers "F.Cu" "F.Paste" "F.Mask")
      (net 188 "/HDMI converter/LT9611_VDD12") (pinfunction "VDD2") (pintype "power_in"))
    (pad "17" smd rect (at -3 3.798 270) (size 0.2 1) (layers "F.Cu" "F.Paste" "F.Mask")
      (net 186 "/HDMI converter/LT9611_RST_N") (pinfunction "RST_N") (pintype "input"))
    (pad "18" smd rect (at -2.601 3.798 270) (size 0.2 1) (layers "F.Cu" "F.Paste" "F.Mask")
      (net 287 "/HDMI converter/LT9611_SCL") (pinfunction "CSCL_GPIO10") (pintype "bidirectional"))
    (pad "19" smd rect (at -2.202 3.798 270) (size 0.2 1) (layers "F.Cu" "F.Paste" "F.Mask")
      (net 288 "/HDMI converter/LT9611_SDA") (pinfunction "CSDA_GPIO11") (pintype "bidirectional"))
    (pad "20" smd rect (at -1.801 3.798 270) (size 0.2 1) (layers "F.Cu" "F.Paste" "F.Mask")
      (net 482 "unconnected-(U3-Pad20)") (pinfunction "SPI_CSN") (pintype "bidirectional+no_connect"))
    (pad "21" smd rect (at -1.401 3.798 270) (size 0.2 1) (layers "F.Cu" "F.Paste" "F.Mask")
      (net 481 "unconnected-(U3-Pad21)") (pinfunction "SPI_MISO") (pintype "bidirectional+no_connect"))
    (pad "22" smd rect (at -1 3.798 270) (size 0.2 1) (layers "F.Cu" "F.Paste" "F.Mask")
      (net 480 "unconnected-(U3-Pad22)") (pinfunction "GPIO4") (pintype "bidirectional+no_connect"))
    (pad "23" smd rect (at -0.6 3.798 270) (size 0.2 1) (layers "F.Cu" "F.Paste" "F.Mask")
      (net 284 "/HDMI converter/LT9611_INTO_GPIO5") (pinfunction "INTIO_GPIO5") (pintype "bidirectional"))
    (pad "24" smd rect (at -0.204 3.798 270) (size 0.2 1) (layers "F.Cu" "F.Paste" "F.Mask")
      (net 285 "/HDMI converter/LT9611_CEC") (pinfunction "CEC_GPIO6") (pintype "bidirectional"))
    (pad "25" smd rect (at 0.2 3.798 270) (size 0.2 1) (layers "F.Cu" "F.Paste" "F.Mask")
      (net 289 "/HDMI converter/I2C_ADDR") (pinfunction "I2C_ADDR") (pintype "input"))
    (pad "26" smd rect (at 0.596 3.798 270) (size 0.2 1) (layers "F.Cu" "F.Paste" "F.Mask")
      (net 184 "/HDMI converter/LT9611_VCC33_IO") (pinfunction "VC33_IO") (pintype "power_in"))
    (pad "27" smd rect (at 0.996 3.798 270) (size 0.2 1) (layers "F.Cu" "F.Paste" "F.Mask")
      (net 298 "/HDMI converter/LT9611_I2S_WS") (pinfunction "I2S_WS_GPIO7") (pintype "bidirectional"))
    (pad "28" smd rect (at 1.396 3.798 270) (size 0.2 1) (layers "F.Cu" "F.Paste" "F.Mask")
      (net 299 "/HDMI converter/LT9611_I2S_SCLK") (pinfunction "I2S_SCLK_GPIO8") (pintype "bidirectional"))
    (pad "29" smd rect (at 1.8 3.798 270) (size 0.2 1) (layers "F.Cu" "F.Paste" "F.Mask")
      (net 300 "/HDMI converter/LT9611_I2S_MCLK") (pinfunction "I2S_MCLK_GPIO9") (pintype "bidirectional"))
    (pad "30" smd rect (at 2.2 3.798 270) (size 0.2 1) (layers "F.Cu" "F.Paste" "F.Mask")
      (net 297 "/HDMI converter/LT9611_I2S_D0_SPDIF") (pinfunction "I2S_D0_SPDIF") (pintype "bidirectional"))
    (pad "31" smd rect (at 2.6 3.798 270) (size 0.2 1) (layers "F.Cu" "F.Paste" "F.Mask")
      (net 188 "/HDMI converter/LT9611_VDD12") (pinfunction "VDD3") (pintype "power_in"))
    (pad "32" smd rect (at 2.999 3.798 270) (size 0.2 1) (layers "F.Cu" "F.Paste" "F.Mask")
      (net 479 "unconnected-(U3-Pad32)") (pinfunction "SPI_MOSI") (pintype "bidirectional+no_connect"))
    (pad "33" smd rect (at 3.798 2.999) (size 0.2 1) (layers "F.Cu" "F.Paste" "F.Mask")
      (net 478 "unconnected-(U3-Pad33)") (pinfunction "SPI_SCK") (pintype "bidirectional+no_connect"))
    (pad "34" smd rect (at 3.798 2.6) (size 0.2 1) (layers "F.Cu" "F.Paste" "F.Mask")
      (net 184 "/HDMI converter/LT9611_VCC33_IO") (pinfunction "VCC33_IO") (pintype "power_in"))
    (pad "35" smd rect (at 3.798 2.2) (size 0.2 1) (layers "F.Cu" "F.Paste" "F.Mask")
      (net 395 "Net-(R27-Pad1)") (pinfunction "HTX_HPD") (pintype "input"))
    (pad "36" smd rect (at 3.798 1.8) (size 0.2 1) (layers "F.Cu" "F.Paste" "F.Mask")
      (net 235 "/HDMI converter/HDMI_SDA") (pinfunction "HTX_DSDA") (pintype "bidirectional"))
    (pad "37" smd rect (at 3.798 1.396) (size 0.2 1) (layers "F.Cu" "F.Paste" "F.Mask")
      (net 232 "/HDMI converter/HDMI_SCL") (pinfunction "HTX_DSCL") (pintype "output"))
    (pad "38" smd rect (at 3.798 0.996) (size 0.2 1) (layers "F.Cu" "F.Paste" "F.Mask")
      (net 207 "/HDMI converter/HDMI_TX_CLK_N") (pinfunction "HTX_C-") (pintype "output"))
    (pad "39" smd rect (at 3.798 0.596) (size 0.2 1) (layers "F.Cu" "F.Paste" "F.Mask")
      (net 205 "/HDMI converter/HDMI_TX_CLK_P") (pinfunction "HTX_C+") (pintype "output"))
    (pad "40" smd rect (at 3.798 0.2) (size 0.2 1) (layers "F.Cu" "F.Paste" "F.Mask")
      (net 204 "/HDMI converter/HDMI_TX_D0_N") (pinfunction "HTX_D0-") (pintype "output"))
    (pad "41" smd rect (at 3.798 -0.204) (size 0.2 1) (layers "F.Cu" "F.Paste" "F.Mask")
      (net 202 "/HDMI converter/HDMI_TX_D0_P") (pinfunction "HTX_D0+") (pintype "output"))
    (pad "42" smd rect (at 3.798 -0.6) (size 0.2 1) (layers "F.Cu" "F.Paste" "F.Mask")
      (net 209 "/HDMI converter/VCOM") (pinfunction "VCOM") (pintype "input"))
    (pad "43" smd rect (at 3.798 -1) (size 0.2 1) (layers "F.Cu" "F.Paste" "F.Mask")
      (net 187 "/HDMI converter/LT9611_VCC33_TX") (pinfunction "VCC33_HTX") (pintype "power_in"))
    (pad "44" smd rect (at 3.798 -1.401) (size 0.2 1) (layers "F.Cu" "F.Paste" "F.Mask")
      (net 191 "/HDMI converter/LT9611_VCC12_TX") (pinfunction "VCC12_HTX") (pintype "power_in"))
    (pad "45" smd rect (at 3.798 -1.801) (size 0.2 1) (layers "F.Cu" "F.Paste" "F.Mask")
      (net 199 "/HDMI converter/HDMI_TX_D1_N") (pinfunction "HTX_D1-") (pintype "output"))
    (pad "46" smd rect (at 3.798 -2.202) (size 0.2 1) (layers "F.Cu" "F.Paste" "F.Mask")
      (net 197 "/HDMI converter/HDMI_TX_D1_P") (pinfunction "HTX_D1+") (pintype "output"))
    (pad "47" smd rect (at 3.798 -2.601) (size 0.2 1) (layers "F.Cu" "F.Paste" "F.Mask")
      (net 196 "/HDMI converter/HDMI_TX_D2_N") (pinfunction "HTX_D2-") (pintype "output"))
    (pad "48" smd rect (at 3.798 -3) (size 0.2 1) (layers "F.Cu" "F.Paste" "F.Mask")
      (net 194 "/HDMI converter/HDMI_TX_D2_P") (pinfunction "HTX_D2+") (pintype "output"))
    (pad "49" smd rect (at 2.999 -3.801 90) (size 0.2 1) (layers "F.Cu" "F.Paste" "F.Mask")
      (net 192 "/HDMI converter/XTALI") (pinfunction "XTALI") (pintype "input"))
    (pad "50" smd rect (at 2.6 -3.801 90) (size 0.2 1) (layers "F.Cu" "F.Paste" "F.Mask")
      (net 190 "/HDMI converter/XTALO") (pinfunction "XTALO") (pintype "output"))
    (pad "51" smd rect (at 2.2 -3.801 90) (size 0.2 1) (layers "F.Cu" "F.Paste" "F.Mask")
      (net 185 "/HDMI converter/LT9611_VCC33_RX") (pinfunction "VCC33_BG") (pintype "power_in"))
    (pad "52" smd rect (at 1.8 -3.801 90) (size 0.2 1) (layers "F.Cu" "F.Paste" "F.Mask")
      (net 394 "Net-(R22-Pad1)") (pinfunction "REXT") (pintype "passive"))
    (pad "53" smd rect (at 1.396 -3.801 90) (size 0.2 1) (layers "F.Cu" "F.Paste" "F.Mask")
      (net 188 "/HDMI converter/LT9611_VDD12") (pinfunction "VCC12_SYSPLL") (pintype "power_in"))
    (pad "54" smd rect (at 0.996 -3.801 90) (size 0.2 1) (layers "F.Cu" "F.Paste" "F.Mask")
      (net 188 "/HDMI converter/LT9611_VDD12") (pinfunction "VDD") (pintype "power_in"))
    (pad "55" smd rect (at 0.596 -3.801 90) (size 0.2 1) (layers "F.Cu" "F.Paste" "F.Mask")
      (net 185 "/HDMI converter/LT9611_VCC33_RX") (pinfunction "VCC33_MRX23") (pintype "power_in"))
    (pad "56" smd rect (at 0.2 -3.801 90) (size 0.2 1) (layers "F.Cu" "F.Paste" "F.Mask")
      (net 189 "/HDMI converter/LT9611_VCC12_RX") (pinfunction "VCC12_MRX23") (pintype "power_in"))
    (pad "57" smd rect (at -0.204 -3.801 90) (size 0.2 1) (layers "F.Cu" "F.Paste" "F.Mask")
      (net 477 "unconnected-(U3-Pad57)") (pinfunction "M3_N2") (pintype "input+no_connect"))
    (pad "58" smd rect (at -0.6 -3.801 90) (size 0.2 1) (layers "F.Cu" "F.Paste" "F.Mask")
      (net 476 "unconnected-(U3-Pad58)") (pinfunction "M3_P2") (pintype "input+no_connect"))
    (pad "59" smd rect (at -1 -3.801 90) (size 0.2 1) (layers "F.Cu" "F.Paste" "F.Mask")
      (net 475 "unconnected-(U3-Pad59)") (pinfunction "M2_N2") (pintype "input+no_connect"))
    (pad "60" smd rect (at -1.401 -3.801 90) (size 0.2 1) (layers "F.Cu" "F.Paste" "F.Mask")
      (net 474 "unconnected-(U3-Pad60)") (pinfunction "M2_P2") (pintype "input+no_connect"))
    (pad "61" smd rect (at -1.801 -3.801 90) (size 0.2 1) (layers "F.Cu" "F.Paste" "F.Mask")
      (net 473 "unconnected-(U3-Pad61)") (pinfunction "MC_N2") (pintype "input+no_connect"))
    (pad "62" smd rect (at -2.202 -3.801 90) (size 0.2 1) (layers "F.Cu" "F.Paste" "F.Mask")
      (net 472 "unconnected-(U3-Pad62)") (pinfunction "MC_P2") (pintype "input+no_connect"))
    (pad "63" smd rect (at -2.601 -3.801 90) (size 0.2 1) (layers "F.Cu" "F.Paste" "F.Mask")
      (net 471 "unconnected-(U3-Pad63)") (pinfunction "M1_N2") (pintype "input+no_connect"))
    (pad "64" smd rect (at -3 -3.801 90) (size 0.2 1) (layers "F.Cu" "F.Paste" "F.Mask")
      (net 470 "unconnected-(U3-Pad64)") (pinfunction "M1_P2") (pintype "input+no_connect"))
    (pad "65" smd rect (at 0 0 270) (size 6.15 6.15) (layers "F.Cu" "F.Mask")
      (net 1 "GND") (pinfunction "GND") (pintype "power_in"))
  )
	(footprint "sa800u-baseboard-hw-footprints:L_Murata_025020_0605Metric" (layer "F.Cu")
    (tedit 61AA2C4F)
    (at 140.45 136.85 -90)
    (property "Author" "Antmicro")
    (property "License" "Apache-2.0")
    (property "MPN" "NFP0QHB242HS2D")
    (property "Manufacturer" "Murata")
    (property "Sheetfile" "hdmi-converter.kicad_sch")
    (property "Sheetname" "HDMI converter")
    (attr smd)
    (fp_text reference "L9" (at -4.57 15.86 -90) (layer "F.SilkS")
      (effects (font (size 0.7 0.7) (thickness 0.15)) (justify left bottom))
    )
    (fp_text value "NFP0QHB242HS2D" (at 0 1.55 -90) (layer "F.Fab")
      (effects (font (size 0.7 0.7) (thickness 0.15)) (justify left bottom))
    )
    (fp_text user "License: Apache-2.0" (at -1.027 5.805 -90) (layer "F.Fab") hide
      (effects (font (size 0.7 0.7) (thickness 0.15)) (justify left bottom))
    )
    (fp_text user "${REFERENCE}" (at -1.027 3.406 -90) (layer "F.Fab") hide
      (effects (font (size 0.7 0.7) (thickness 0.15)) (justify left bottom))
    )
    (fp_text user "Author: Antmicro" (at -1.027 4.605 -90) (layer "F.Fab") hide
      (effects (font (size 0.7 0.7) (thickness 0.15)) (justify left bottom))
    )
    (fp_line (start -0.276 0.45) (end 0.276 0.45) (layer "F.SilkS") (width 0.15))
    (fp_line (start 0.276 -0.45) (end -0.276 -0.45) (layer "F.SilkS") (width 0.15))
    (fp_circle (center -0.5 -0.5) (end -0.449 -0.5) (layer "F.SilkS") (width 0.15) (fill solid))
    (fp_rect (start -0.5 -0.6) (end 0.5 0.6) (layer "F.CrtYd") (width 0.05) (fill none))
    (fp_line (start 0.275 0.349) (end 0.275 -0.351) (layer "F.Fab") (width 0.15))
    (fp_line (start 0.275 -0.351) (end -0.277 -0.351) (layer "F.Fab") (width 0.15))
    (fp_line (start -0.277 -0.351) (end -0.277 0.349) (layer "F.Fab") (width 0.15))
    (fp_line (start -0.277 0.349) (end 0.275 0.349) (layer "F.Fab") (width 0.15))
    (pad "1" smd rect (at -0.25 -0.24 270) (size 0.3 0.23) (layers "F.Cu" "F.Paste" "F.Mask")
      (net 201 "/HDMI converter/HDMI_TX0_P") (pinfunction "1") (pintype "passive"))
    (pad "2" smd rect (at 0.248 -0.24 270) (size 0.3 0.23) (layers "F.Cu" "F.Paste" "F.Mask")
      (net 239 "/HDMI converter/HDMI_TX0_CONN_P") (pinfunction "2") (pintype "passive"))
    (pad "3" smd rect (at 0.248 0.239 270) (size 0.3 0.23) (layers "F.Cu" "F.Paste" "F.Mask")
      (net 236 "/HDMI converter/HDMI_TX0_CONN_N") (pinfunction "3") (pintype "passive"))
    (pad "4" smd rect (at -0.25 0.239 270) (size 0.3 0.23) (layers "F.Cu" "F.Paste" "F.Mask")
      (net 203 "/HDMI converter/HDMI_TX0_N") (pinfunction "4") (pintype "passive"))
  )
)
